(kicad_pcb
	(version 20260206)
	(generator "pcbnew")
	(generator_version "10.0")
	(general
		(thickness 1.6)
		(legacy_teardrops no)
	)
	(paper "A4")
	(title_block
		(title "dpb — 14545-sa.0730WZS0815.brd")
		(comment 1 "Honey Badger (Wiwynn) / footprints 950-955 of 1066")
	)
	(layers
		(0 "F.Cu" signal "TOP")
		(4 "In1.Cu" signal "L2GND")
		(6 "In2.Cu" signal "L3")
		(8 "In3.Cu" signal "L4VCC")
		(10 "In4.Cu" signal "L5VCC")
		(12 "In5.Cu" signal "L6")
		(14 "In6.Cu" signal "L7GND")
		(2 "B.Cu" signal "BOTTOM")
		(9 "F.Adhes" user "F.Adhesive")
		(11 "B.Adhes" user "B.Adhesive")
		(13 "F.Paste" user "Package Geometry/Pastemask Top")
		(15 "B.Paste" user "Package Geometry/Pastemask Bottom")
		(5 "F.SilkS" user "Ref Des/Silkscreen Top")
		(7 "B.SilkS" user "Ref Des/Silkscreen Bottom")
		(1 "F.Mask" user "Board Geometry/Soldermask Top")
		(3 "B.Mask" user "Board Geometry/Soldermask Bottom")
		(17 "Dwgs.User" user "User.Drawings")
		(19 "Cmts.User" user "User.Comments")
		(21 "Eco1.User" user "User.Eco1")
		(23 "Eco2.User" user "User.Eco2")
		(25 "Edge.Cuts" user "Board Geometry/Outline")
		(27 "Margin" user)
		(31 "F.CrtYd" user "Package Geometry/Place Bound Top")
		(29 "B.CrtYd" user "Package Geometry/Place Bound Bottom")
		(35 "F.Fab" user "Ref Des/Assembly Top")
		(33 "B.Fab" user "Ref Des/Assembly Bottom")
	)
	(footprint ""
		(layer "F.Cu")
		(at 34.543746 -433.0827 180)
		(property "Reference" "R462"
			(at 0 0 180)
			(layer "F.SilkS")
			(hide yes)
			(effects
				(font
					(size 1.27 1.27)
				)
			)
		)
		(property "Value" "4K7R2J-2-GP"
			(at 0.064008 -3.993896 180)
			(unlocked yes)
			(layer "F.Fab")
			(hide yes)
			(effects
				(font
					(size 1.016 1.016)
					(thickness 0.1524)
				)
			)
		)
		(property "Device Type" "R402H16"
			(at 0.064008 -5.517896 180)
			(unlocked yes)
			(layer "F.Fab")
			(hide yes)
			(effects
				(font
					(size 1.016 1.016)
					(thickness 0.1524)
				)
			)
		)
		(duplicate_pad_numbers_are_jumpers no)
		(fp_line
			(start 0.508 -0.9398)
			(end -0.508 -0.9398)
			(stroke
				(width 0.1524)
				(type default)
			)
			(layer "F.SilkS")
		)
		(fp_line
			(start -0.508 -0.9398)
			(end -0.508 0.9398)
			(stroke
				(width 0.1524)
				(type default)
			)
			(layer "F.SilkS")
		)
		(fp_rect
			(start -0.508 0.9398)
			(end 0.508 -0.9398)
			(stroke
				(width 0)
				(type default)
			)
			(fill no)
			(layer "F.CrtYd")
		)
		(fp_rect
			(start -0.508 0.9398)
			(end 0.508 -0.9398)
			(stroke
				(width 0)
				(type default)
			)
			(fill no)
			(layer "F.Fab")
		)
		(pad "1" smd custom
			(at 0 -0.4445 180)
			(size 0.1397 0.1397)
			(layers "F.Cu" "F.Mask" "F.Paste")
			(net "P3V3")
			(options
				(clearance outline)
				(anchor circle)
			)
			(primitives
				(gr_poly
					(pts
						(arc
							(start -0.1778 -0.2794)
							(mid -0.249642 -0.249642)
							(end -0.2794 -0.1778)
						)
						(arc
							(start -0.2794 0.1778)
							(mid -0.249642 0.249642)
							(end -0.1778 0.2794)
						)
						(arc
							(start 0.1778 0.2794)
							(mid 0.249642 0.249642)
							(end 0.2794 0.1778)
						)
						(arc
							(start 0.2794 -0.1778)
							(mid 0.249642 -0.249642)
							(end 0.1778 -0.2794)
						)
					)
					(width 0)
					(fill yes)
				)
			)
		)
		(pad "2" smd custom
			(at 0 0.4445 180)
			(size 0.1397 0.1397)
			(layers "F.Cu" "F.Mask" "F.Paste")
			(net "SAS_EXP_A_PWR10")
			(options
				(clearance outline)
				(anchor circle)
			)
			(primitives
				(gr_poly
					(pts
						(arc
							(start -0.1778 -0.2794)
							(mid -0.249642 -0.249642)
							(end -0.2794 -0.1778)
						)
						(arc
							(start -0.2794 0.1778)
							(mid -0.249642 0.249642)
							(end -0.1778 0.2794)
						)
						(arc
							(start 0.1778 0.2794)
							(mid 0.249642 0.249642)
							(end 0.2794 0.1778)
						)
						(arc
							(start 0.2794 -0.1778)
							(mid 0.249642 -0.249642)
							(end 0.1778 -0.2794)
						)
					)
					(width 0)
					(fill yes)
				)
			)
		)
	)
	(footprint ""
		(layer "F.Cu")
		(at 195.58 -188.087 180)
		(property "Reference" "R411"
			(at 0 0 180)
			(layer "F.SilkS")
			(hide yes)
			(effects
				(font
					(size 1.27 1.27)
				)
			)
		)
		(property "Value" "0R2J-2-GP"
			(at 0.064008 -3.993896 180)
			(unlocked yes)
			(layer "F.Fab")
			(hide yes)
			(effects
				(font
					(size 1.016 1.016)
					(thickness 0.1524)
				)
			)
		)
		(property "Device Type" "R402H16"
			(at 0.064008 -5.517896 180)
			(unlocked yes)
			(layer "F.Fab")
			(hide yes)
			(effects
				(font
					(size 1.016 1.016)
					(thickness 0.1524)
				)
			)
		)
		(duplicate_pad_numbers_are_jumpers no)
		(fp_line
			(start 0.508 -0.9398)
			(end -0.508 -0.9398)
			(stroke
				(width 0.1524)
				(type default)
			)
			(layer "F.SilkS")
		)
		(fp_line
			(start -0.508 -0.9398)
			(end -0.508 0.9398)
			(stroke
				(width 0.1524)
				(type default)
			)
			(layer "F.SilkS")
		)
		(fp_rect
			(start -0.508 0.9398)
			(end 0.508 -0.9398)
			(stroke
				(width 0)
				(type default)
			)
			(fill no)
			(layer "F.CrtYd")
		)
		(fp_rect
			(start -0.508 0.9398)
			(end 0.508 -0.9398)
			(stroke
				(width 0)
				(type default)
			)
			(fill no)
			(layer "F.Fab")
		)
		(pad "1" smd custom
			(at 0 -0.4445 180)
			(size 0.1397 0.1397)
			(layers "F.Cu" "F.Mask" "F.Paste")
			(net "SW_HDD3_G")
			(options
				(clearance outline)
				(anchor circle)
			)
			(primitives
				(gr_poly
					(pts
						(arc
							(start -0.1778 -0.2794)
							(mid -0.249642 -0.249642)
							(end -0.2794 -0.1778)
						)
						(arc
							(start -0.2794 0.1778)
							(mid -0.249642 0.249642)
							(end -0.1778 0.2794)
						)
						(arc
							(start 0.1778 0.2794)
							(mid 0.249642 0.249642)
							(end 0.2794 0.1778)
						)
						(arc
							(start 0.2794 -0.1778)
							(mid 0.249642 -0.249642)
							(end 0.1778 -0.2794)
						)
					)
					(width 0)
					(fill yes)
				)
			)
		)
		(pad "2" smd custom
			(at 0 0.4445 180)
			(size 0.1397 0.1397)
			(layers "F.Cu" "F.Mask" "F.Paste")
			(net "SW_HDD3_R")
			(options
				(clearance outline)
				(anchor circle)
			)
			(primitives
				(gr_poly
					(pts
						(arc
							(start -0.1778 -0.2794)
							(mid -0.249642 -0.249642)
							(end -0.2794 -0.1778)
						)
						(arc
							(start -0.2794 0.1778)
							(mid -0.249642 0.249642)
							(end -0.1778 0.2794)
						)
						(arc
							(start 0.1778 0.2794)
							(mid 0.249642 0.249642)
							(end 0.2794 0.1778)
						)
						(arc
							(start 0.2794 -0.1778)
							(mid 0.249642 -0.249642)
							(end 0.1778 -0.2794)
						)
					)
					(width 0)
					(fill yes)
				)
			)
		)
	)
	(footprint ""
		(layer "F.Cu")
		(at 5.969 -32.004 -90)
		(property "Reference" "PC69"
			(at 0 0 270)
			(layer "F.SilkS")
			(hide yes)
			(effects
				(font
					(size 1.27 1.27)
				)
			)
		)
		(property "Value" "SC22U25V5MX-GP"
			(at -0.0762 -6.1214 270)
			(unlocked yes)
			(layer "F.Fab")
			(hide yes)
			(effects
				(font
					(size 1.016 1.016)
					(thickness 0.1524)
				)
			)
		)
		(property "Device Type" "C805H58"
			(at -0.0762 -8.1534 270)
			(unlocked yes)
			(layer "F.Fab")
			(hide yes)
			(effects
				(font
					(size 1.016 1.016)
					(thickness 0.1524)
				)
			)
		)
		(duplicate_pad_numbers_are_jumpers no)
		(fp_line
			(start 0.635 0)
			(end -0.635 0)
			(stroke
				(width 0.508)
				(type default)
			)
			(layer "F.SilkS")
		)
		(fp_rect
			(start -0.9652 1.778)
			(end 0.9652 -1.778)
			(stroke
				(width 0)
				(type default)
			)
			(fill no)
			(layer "F.CrtYd")
		)
		(fp_poly
			(pts
				(xy -0.9652 -1.778) (xy 0.9652 -1.778) (xy 0.9652 1.778) (xy -0.9652 1.778)
			)
			(stroke
				(width 0)
				(type default)
			)
			(fill no)
			(layer "F.Fab")
		)
		(pad "1" smd rect
			(at 0 -0.9652 270)
			(size 1.397 1.143)
			(layers "F.Cu" "F.Mask" "F.Paste")
			(net "P12V")
		)
		(pad "2" smd rect
			(at 0 0.9652 270)
			(size 1.397 1.143)
			(layers "F.Cu" "F.Mask" "F.Paste")
			(net "GND")
		)
	)
	(footprint ""
		(layer "F.Cu")
		(at 227.2792 -433.578)
		(property "Reference" "PC42"
			(at 0 0 0)
			(layer "F.SilkS")
			(hide yes)
			(effects
				(font
					(size 1.27 1.27)
				)
			)
		)
		(property "Value" "SC22P50V3JN-GP"
			(at 0 -2.8194 0)
			(unlocked yes)
			(layer "F.Fab")
			(hide yes)
			(effects
				(font
					(size 1.016 1.016)
					(thickness 0.1524)
				)
			)
		)
		(property "Device Type" "C603H36"
			(at 0 -4.3434 0)
			(unlocked yes)
			(layer "F.Fab")
			(hide yes)
			(effects
				(font
					(size 1.016 1.016)
					(thickness 0.1524)
				)
			)
		)
		(duplicate_pad_numbers_are_jumpers no)
		(fp_line
			(start 0.508 0)
			(end -0.508 0)
			(stroke
				(width 0.2032)
				(type default)
			)
			(layer "F.SilkS")
		)
		(fp_rect
			(start -0.5842 1.3335)
			(end 0.5842 -1.3335)
			(stroke
				(width 0)
				(type default)
			)
			(fill no)
			(layer "F.CrtYd")
		)
		(fp_rect
			(start -0.5842 1.3335)
			(end 0.5842 -1.3335)
			(stroke
				(width 0)
				(type default)
			)
			(fill no)
			(layer "F.Fab")
		)
		(pad "1" smd custom
			(at 0 -0.762)
			(size 0.2159 0.2159)
			(layers "F.Cu" "F.Mask" "F.Paste")
			(net "P3V3_LX_COOPER")
			(options
				(clearance outline)
				(anchor circle)
			)
			(primitives
				(gr_poly
					(pts
						(arc
							(start -0.3302 -0.4318)
							(mid -0.402042 -0.402042)
							(end -0.4318 -0.3302)
						)
						(arc
							(start -0.4318 0.3302)
							(mid -0.402042 0.402042)
							(end -0.3302 0.4318)
						)
						(arc
							(start 0.3302 0.4318)
							(mid 0.402042 0.402042)
							(end 0.4318 0.3302)
						)
						(arc
							(start 0.4318 -0.3302)
							(mid 0.402042 -0.402042)
							(end 0.3302 -0.4318)
						)
					)
					(width 0)
					(fill yes)
				)
			)
		)
		(pad "2" smd custom
			(at 0 0.762)
			(size 0.2159 0.2159)
			(layers "F.Cu" "F.Mask" "F.Paste")
			(net "P3V3_FB")
			(options
				(clearance outline)
				(anchor circle)
			)
			(primitives
				(gr_poly
					(pts
						(arc
							(start -0.3302 -0.4318)
							(mid -0.402042 -0.402042)
							(end -0.4318 -0.3302)
						)
						(arc
							(start -0.4318 0.3302)
							(mid -0.402042 0.402042)
							(end -0.3302 0.4318)
						)
						(arc
							(start 0.3302 0.4318)
							(mid 0.402042 0.402042)
							(end 0.4318 0.3302)
						)
						(arc
							(start 0.4318 -0.3302)
							(mid 0.402042 -0.402042)
							(end 0.3302 -0.4318)
						)
					)
					(width 0)
					(fill yes)
				)
			)
		)
	)
	(footprint ""
		(layer "F.Cu")
		(at 33.908746 -343.2937 90)
		(property "Reference" "Q45"
			(at 0 0 90)
			(layer "F.SilkS")
			(hide yes)
			(effects
				(font
					(size 1.27 1.27)
				)
			)
		)
		(property "Value" "PMBS3904-1-GP"
			(at 0 -9.0932 90)
			(unlocked yes)
			(layer "F.Fab")
			(hide yes)
			(effects
				(font
					(size 1.016 1.016)
					(thickness 0.1524)
				)
			)
		)
		(property "Device Type" "SOT-23-10H44"
			(at 0 -10.6172 90)
			(unlocked yes)
			(layer "F.Fab")
			(hide yes)
			(effects
				(font
					(size 1.016 1.016)
					(thickness 0.1524)
				)
			)
		)
		(duplicate_pad_numbers_are_jumpers no)
		(fp_line
			(start 1.651 -1.778)
			(end -1.651 -1.778)
			(stroke
				(width 0.1524)
				(type default)
			)
			(layer "F.SilkS")
		)
		(fp_line
			(start -1.651 -1.778)
			(end -1.651 1.778)
			(stroke
				(width 0.1524)
				(type default)
			)
			(layer "F.SilkS")
		)
		(fp_line
			(start 1.651 1.778)
			(end 1.651 -1.778)
			(stroke
				(width 0.1524)
				(type default)
			)
			(layer "F.SilkS")
		)
		(fp_line
			(start -1.651 1.778)
			(end 1.651 1.778)
			(stroke
				(width 0.1524)
				(type default)
			)
			(layer "F.SilkS")
		)
		(fp_line
			(start -0.9906 1.86309)
			(end -0.701294 2.15265)
			(stroke
				(width 0.0127)
				(type default)
			)
			(layer "F.SilkS")
		)
		(fp_line
			(start -0.994156 1.8669)
			(end -0.987044 1.8669)
			(stroke
				(width 0.0127)
				(type default)
			)
			(layer "F.SilkS")
		)
		(fp_line
			(start -1.003808 1.876552)
			(end -0.977646 1.876552)
			(stroke
				(width 0.0127)
				(type default)
			)
			(layer "F.SilkS")
		)
		(fp_line
			(start -0.635 1.8796)
			(end -1.7526 1.8796)
			(stroke
				(width 0.3302)
				(type default)
			)
			(layer "F.SilkS")
		)
		(fp_line
			(start -1.7526 1.8796)
			(end -1.7526 0.9906)
			(stroke
				(width 0.3302)
				(type default)
			)
			(layer "F.SilkS")
		)
		(fp_line
			(start -1.013206 1.88595)
			(end -0.967994 1.88595)
			(stroke
				(width 0.0127)
				(type default)
			)
			(layer "F.SilkS")
		)
		(fp_line
			(start -1.022858 1.895602)
			(end -0.958596 1.895602)
			(stroke
				(width 0.0127)
				(type default)
			)
			(layer "F.SilkS")
		)
		(fp_line
			(start -1.032256 1.905)
			(end -0.948944 1.905)
			(stroke
				(width 0.0127)
				(type default)
			)
			(layer "F.SilkS")
		)
		(fp_line
			(start -1.041908 1.914652)
			(end -0.939546 1.914652)
			(stroke
				(width 0.0127)
				(type default)
			)
			(layer "F.SilkS")
		)
		(fp_line
			(start -1.051306 1.92405)
			(end -0.929894 1.92405)
			(stroke
				(width 0.0127)
				(type default)
			)
			(layer "F.SilkS")
		)
		(fp_line
			(start -1.060958 1.933702)
			(end -0.920496 1.933702)
			(stroke
				(width 0.0127)
				(type default)
			)
			(layer "F.SilkS")
		)
		(fp_line
			(start -1.070356 1.9431)
			(end -0.910844 1.9431)
			(stroke
				(width 0.0127)
				(type default)
			)
			(layer "F.SilkS")
		)
		(fp_line
			(start -1.080008 1.952752)
			(end -0.901446 1.952752)
			(stroke
				(width 0.0127)
				(type default)
			)
			(layer "F.SilkS")
		)
		(fp_line
			(start -1.089406 1.96215)
			(end -0.891794 1.96215)
			(stroke
				(width 0.0127)
				(type default)
			)
			(layer "F.SilkS")
		)
		(fp_line
			(start -1.099058 1.971802)
			(end -0.882396 1.971802)
			(stroke
				(width 0.0127)
				(type default)
			)
			(layer "F.SilkS")
		)
		(fp_line
			(start -1.108456 1.9812)
			(end -0.872744 1.9812)
			(stroke
				(width 0.0127)
				(type default)
			)
			(layer "F.SilkS")
		)
		(fp_line
			(start -1.118108 1.990852)
			(end -0.863346 1.990852)
			(stroke
				(width 0.0127)
				(type default)
			)
			(layer "F.SilkS")
		)
		(fp_line
			(start -1.127506 2.00025)
			(end -0.853694 2.00025)
			(stroke
				(width 0.0127)
				(type default)
			)
			(layer "F.SilkS")
		)
		(fp_line
			(start -1.137158 2.009902)
			(end -0.844296 2.009902)
			(stroke
				(width 0.0127)
				(type default)
			)
			(layer "F.SilkS")
		)
		(fp_line
			(start -1.146556 2.0193)
			(end -0.834644 2.0193)
			(stroke
				(width 0.0127)
				(type default)
			)
			(layer "F.SilkS")
		)
		(fp_line
			(start -1.156208 2.028952)
			(end -0.825246 2.028952)
			(stroke
				(width 0.0127)
				(type default)
			)
			(layer "F.SilkS")
		)
		(fp_line
			(start -1.165606 2.03835)
			(end -0.815594 2.03835)
			(stroke
				(width 0.0127)
				(type default)
			)
			(layer "F.SilkS")
		)
		(fp_line
			(start -1.175258 2.048002)
			(end -0.806196 2.048002)
			(stroke
				(width 0.0127)
				(type default)
			)
			(layer "F.SilkS")
		)
		(fp_line
			(start -1.184656 2.0574)
			(end -0.796544 2.0574)
			(stroke
				(width 0.0127)
				(type default)
			)
			(layer "F.SilkS")
		)
		(fp_line
			(start -1.194308 2.067052)
			(end -0.787146 2.067052)
			(stroke
				(width 0.0127)
				(type default)
			)
			(layer "F.SilkS")
		)
		(fp_line
			(start -1.203706 2.07645)
			(end -0.777494 2.07645)
			(stroke
				(width 0.0127)
				(type default)
			)
			(layer "F.SilkS")
		)
		(fp_line
			(start -1.213358 2.086102)
			(end -0.768096 2.086102)
			(stroke
				(width 0.0127)
				(type default)
			)
			(layer "F.SilkS")
		)
		(fp_line
			(start -1.222756 2.0955)
			(end -0.758444 2.0955)
			(stroke
				(width 0.0127)
				(type default)
			)
			(layer "F.SilkS")
		)
		(fp_line
			(start -1.232408 2.105152)
			(end -0.749046 2.105152)
			(stroke
				(width 0.0127)
				(type default)
			)
			(layer "F.SilkS")
		)
		(fp_line
			(start -1.241806 2.11455)
			(end -0.739394 2.11455)
			(stroke
				(width 0.0127)
				(type default)
			)
			(layer "F.SilkS")
		)
		(fp_line
			(start -1.251458 2.124202)
			(end -0.729996 2.124202)
			(stroke
				(width 0.0127)
				(type default)
			)
			(layer "F.SilkS")
		)
		(fp_line
			(start -1.260856 2.1336)
			(end -0.720344 2.1336)
			(stroke
				(width 0.0127)
				(type default)
			)
			(layer "F.SilkS")
		)
		(fp_line
			(start -0.719074 2.145538)
			(end -1.265936 2.14122)
			(stroke
				(width 0.0127)
				(type default)
			)
			(layer "F.SilkS")
		)
		(fp_line
			(start -1.279398 2.152142)
			(end -0.9906 1.86309)
			(stroke
				(width 0.0127)
				(type default)
			)
			(layer "F.SilkS")
		)
		(fp_line
			(start -0.71628 2.15265)
			(end -1.26492 2.15265)
			(stroke
				(width 0.0127)
				(type default)
			)
			(layer "F.SilkS")
		)
		(fp_line
			(start -1.279144 2.15265)
			(end -0.701294 2.15265)
			(stroke
				(width 0.0127)
				(type default)
			)
			(layer "F.SilkS")
		)
		(fp_poly
			(pts
				(xy -1.285748 2.159) (xy -1.285748 1.8796) (xy -1.778 1.8796) (xy -1.778 -1.8796) (xy 1.778 -1.8796)
				(xy 1.778 1.8796) (xy -0.694944 1.8796) (xy -0.694944 2.159)
			)
			(stroke
				(width 0)
				(type default)
			)
			(fill no)
			(layer "F.CrtYd")
		)
		(fp_poly
			(pts
				(xy -1.285748 2.159) (xy -1.285748 1.8796) (xy -1.778 1.8796) (xy -1.778 -1.8796) (xy 1.778 -1.8796)
				(xy 1.778 1.8796) (xy -0.694944 1.8796) (xy -0.694944 2.159)
			)
			(stroke
				(width 0)
				(type default)
			)
			(fill no)
			(layer "F.Fab")
		)
		(pad "1" smd rect
			(at -0.98425 0.9525 90)
			(size 0.762 1.143)
			(layers "F.Cu" "F.Mask" "F.Paste")
			(net "FLT_HDD11_B")
		)
		(pad "2" smd rect
			(at 0.98425 0.9525 90)
			(size 0.762 1.143)
			(layers "F.Cu" "F.Mask" "F.Paste")
			(net "GND")
		)
		(pad "3" smd rect
			(at 0 -0.9525 90)
			(size 0.762 1.143)
			(layers "F.Cu" "F.Mask" "F.Paste")
			(net "DRIVE_ACT_11")
		)
	)
	(footprint ""
		(layer "F.Cu")
		(at 45.465746 -18.5547)
		(property "Reference" "PC15"
			(at 0 0 0)
			(layer "F.SilkS")
			(hide yes)
			(effects
				(font
					(size 1.27 1.27)
				)
			)
		)
		(property "Value" "SCD1U25V2KX-GP"
			(at 1.1811 -2.7051 0)
			(unlocked yes)
			(layer "F.Fab")
			(hide yes)
			(effects
				(font
					(size 1.016 1.016)
					(thickness 0.1524)
				)
			)
		)
		(property "Device Type" "C402H22"
			(at 1.1811 -4.2291 0)
			(unlocked yes)
			(layer "F.Fab")
			(hide yes)
			(effects
				(font
					(size 1.016 1.016)
					(thickness 0.1524)
				)
			)
		)
		(duplicate_pad_numbers_are_jumpers no)
		(fp_rect
			(start -0.4318 0.9525)
			(end 0.4318 -0.9525)
			(stroke
				(width 0)
				(type default)
			)
			(fill no)
			(layer "F.CrtYd")
		)
		(fp_rect
			(start -0.4318 0.9525)
			(end 0.4318 -0.9525)
			(stroke
				(width 0)
				(type default)
			)
			(fill no)
			(layer "F.Fab")
		)
		(pad "1" smd custom
			(at 0 -0.4445)
			(size 0.1524 0.1524)
			(layers "F.Cu" "F.Mask" "F.Paste")
			(net "P5VB_VBST_NET")
			(options
				(clearance outline)
				(anchor circle)
			)
			(primitives
				(gr_poly
					(pts
						(arc
							(start 0.3048 -0.2032)
							(mid 0.275042 -0.275042)
							(end 0.2032 -0.3048)
						)
						(arc
							(start -0.2032 -0.3048)
							(mid -0.275042 -0.275042)
							(end -0.3048 -0.2032)
						)
						(arc
							(start -0.3048 0.2032)
							(mid -0.275042 0.275042)
							(end -0.2032 0.3048)
						)
						(arc
							(start 0.2032 0.3048)
							(mid 0.275042 0.275042)
							(end 0.3048 0.2032)
						)
					)
					(width 0)
					(fill yes)
				)
			)
		)
		(pad "2" smd custom
			(at 0 0.4445)
			(size 0.1524 0.1524)
			(layers "F.Cu" "F.Mask" "F.Paste")
			(net "P5VB_LL")
			(options
				(clearance outline)
				(anchor circle)
			)
			(primitives
				(gr_poly
					(pts
						(arc
							(start 0.3048 -0.2032)
							(mid 0.275042 -0.275042)
							(end 0.2032 -0.3048)
						)
						(arc
							(start -0.2032 -0.3048)
							(mid -0.275042 -0.275042)
							(end -0.3048 -0.2032)
						)
						(arc
							(start -0.3048 0.2032)
							(mid -0.275042 0.275042)
							(end -0.2032 0.3048)
						)
						(arc
							(start 0.2032 0.3048)
							(mid 0.275042 0.275042)
							(end 0.3048 0.2032)
						)
					)
					(width 0)
					(fill yes)
				)
			)
		)
	)
)
